# S9S_MB_2U (Grand Teton) — schematic netlist excerpt (pin names and nets, part order shuffled) for the footprints in the layout excerpt that follows; sources: Cadence DE-HDL packaged netlist, KiCad conversion of 03242023_DA0F0TMBIJ0_F0T_Motherboard_J_brd_V01_OCP.brd

PR358  Q_RES  3.57K 1% CHIP  pkg 0402LF  page 278 : A = GND ; B = PVCCD_HV_CPU0_ADDR
PR703  Q_RES  0 5% EMPTY  pkg 0402LF  page 289 : A = P3V3 ; B = PVCCFA_EHV_FIVRA_CPU1_PVCC1

(kicad_pcb
	(version 20260206)
	(generator "pcbnew")
	(generator_version "10.0")
	(general
		(thickness 1.6)
		(legacy_teardrops no)
	)
	(paper "A4")
	(title_block
		(title "03242023_DA0F0TMBIJ0_F0T_Motherboard_J_brd_V01_OCP.brd")
		(comment 1 "Grand Teton / footprints 2369-2370 of 6105")
	)
	(layers
		(0 "F.Cu" signal "TOP")
		(4 "In1.Cu" signal "GND")
		(6 "In2.Cu" signal "IN1")
		(8 "In3.Cu" signal "GND1")
		(10 "In4.Cu" signal "IN2")
		(12 "In5.Cu" signal "GND2")
		(14 "In6.Cu" signal "IN3")
		(16 "In7.Cu" signal "GND3")
		(18 "In8.Cu" signal "VCC")
		(20 "In9.Cu" signal "VCC1")
		(22 "In10.Cu" signal "GND4")
		(24 "In11.Cu" signal "IN4")
		(26 "In12.Cu" signal "GND5")
		(28 "In13.Cu" signal "IN5")
		(30 "In14.Cu" signal "GND6")
		(32 "In15.Cu" signal "IN6")
		(34 "In16.Cu" signal "GND7")
		(2 "B.Cu" signal "BOTTOM")
		(9 "F.Adhes" user "F.Adhesive")
		(11 "B.Adhes" user "B.Adhesive")
		(13 "F.Paste" user "Package Geometry/Pastemask Top")
		(15 "B.Paste" user "Package Geometry/Pastemask Bottom")
		(5 "F.SilkS" user "Ref Des/Silkscreen Top")
		(7 "B.SilkS" user "Ref Des/Silkscreen Bottom")
		(1 "F.Mask" user "Board Geometry/Soldermask Top")
		(3 "B.Mask" user "Board Geometry/Soldermask Bottom")
		(17 "Dwgs.User" user "User.Drawings")
		(19 "Cmts.User" user "User.Comments")
		(21 "Eco1.User" user "User.Eco1")
		(23 "Eco2.User" user "User.Eco2")
		(25 "Edge.Cuts" user "Board Geometry/Outline")
		(27 "Margin" user)
		(31 "F.CrtYd" user "Package Geometry/Place Bound Top")
		(29 "B.CrtYd" user "Package Geometry/Place Bound Bottom")
		(35 "F.Fab" user "Ref Des/Assembly Top")
		(33 "B.Fab" user "Ref Des/Assembly Bottom")
	)
	(footprint ""
		(layer "F.Cu")
		(at 428.226474 -126.81966)
		(property "Reference" "PR358"
			(at 0 0 0)
			(layer "F.SilkS")
			(hide yes)
			(effects
				(font
					(size 1.27 1.27)
				)
			)
		)
		(property "Value" ""
			(at 0 0 0)
			(layer "F.Fab")
			(effects
				(font
					(size 1.27 1.27)
				)
			)
		)
		(duplicate_pad_numbers_are_jumpers no)
		(fp_line
			(start -0.7874 -0.4064)
			(end 0.7874 -0.4064)
			(stroke
				(width 0.1524)
				(type default)
			)
			(layer "F.SilkS")
		)
		(fp_line
			(start -0.7874 0.4064)
			(end -0.7874 -0.4064)
			(stroke
				(width 0.1524)
				(type default)
			)
			(layer "F.SilkS")
		)
		(fp_line
			(start 0.7874 -0.4064)
			(end 0.7874 0.4064)
			(stroke
				(width 0.1524)
				(type default)
			)
			(layer "F.SilkS")
		)
		(fp_line
			(start 0.7874 0.4064)
			(end -0.7874 0.4064)
			(stroke
				(width 0.1524)
				(type default)
			)
			(layer "F.SilkS")
		)
		(fp_line
			(start -0.67945 -0.305054)
			(end -0.12065 -0.305054)
			(stroke
				(width 0.1)
				(type default)
			)
			(layer "F.Fab")
		)
		(fp_line
			(start -0.67945 0.3048)
			(end -0.67945 -0.305054)
			(stroke
				(width 0.1)
				(type default)
			)
			(layer "F.Fab")
		)
		(fp_line
			(start -0.12065 -0.305054)
			(end -0.12065 -0.2794)
			(stroke
				(width 0.1)
				(type default)
			)
			(layer "F.Fab")
		)
		(fp_line
			(start -0.12065 -0.2794)
			(end 0.12065 -0.2794)
			(stroke
				(width 0.1)
				(type default)
			)
			(layer "F.Fab")
		)
		(fp_line
			(start -0.12065 0.2794)
			(end -0.12065 0.3048)
			(stroke
				(width 0.1)
				(type default)
			)
			(layer "F.Fab")
		)
		(fp_line
			(start -0.12065 0.3048)
			(end -0.67945 0.3048)
			(stroke
				(width 0.1)
				(type default)
			)
			(layer "F.Fab")
		)
		(fp_line
			(start 0.120396 0.2794)
			(end -0.12065 0.2794)
			(stroke
				(width 0.1)
				(type default)
			)
			(layer "F.Fab")
		)
		(fp_line
			(start 0.120396 0.3048)
			(end 0.120396 0.2794)
			(stroke
				(width 0.1)
				(type default)
			)
			(layer "F.Fab")
		)
		(fp_line
			(start 0.12065 -0.3048)
			(end 0.67945 -0.3048)
			(stroke
				(width 0.1)
				(type default)
			)
			(layer "F.Fab")
		)
		(fp_line
			(start 0.12065 -0.2794)
			(end 0.12065 -0.3048)
			(stroke
				(width 0.1)
				(type default)
			)
			(layer "F.Fab")
		)
		(fp_line
			(start 0.67945 -0.3048)
			(end 0.67945 0.3048)
			(stroke
				(width 0.1)
				(type default)
			)
			(layer "F.Fab")
		)
		(fp_line
			(start 0.67945 0.3048)
			(end 0.120396 0.3048)
			(stroke
				(width 0.1)
				(type default)
			)
			(layer "F.Fab")
		)
		(pad "1" smd circle
			(at -0.40005 0)
			(size 0 0)
			(layers "F.Cu" "F.Mask" "F.Paste")
			(net "GND")
		)
		(pad "2" smd circle
			(at 0.40005 0)
			(size 0 0)
			(layers "F.Cu" "F.Mask" "F.Paste")
			(net "PVCCD_HV_CPU0_ADDR")
		)
	)
	(footprint ""
		(layer "F.Cu")
		(at 167.064944 -353.76358)
		(property "Reference" "PR703"
			(at 0 0 0)
			(layer "F.SilkS")
			(hide yes)
			(effects
				(font
					(size 1.27 1.27)
				)
			)
		)
		(property "Value" ""
			(at 0 0 0)
			(layer "F.Fab")
			(effects
				(font
					(size 1.27 1.27)
				)
			)
		)
		(duplicate_pad_numbers_are_jumpers no)
		(fp_line
			(start -0.7874 -0.4064)
			(end 0.7874 -0.4064)
			(stroke
				(width 0.1524)
				(type default)
			)
			(layer "F.SilkS")
		)
		(fp_line
			(start -0.7874 0.4064)
			(end -0.7874 -0.4064)
			(stroke
				(width 0.1524)
				(type default)
			)
			(layer "F.SilkS")
		)
		(fp_line
			(start 0.7874 -0.4064)
			(end 0.7874 0.4064)
			(stroke
				(width 0.1524)
				(type default)
			)
			(layer "F.SilkS")
		)
		(fp_line
			(start 0.7874 0.4064)
			(end -0.7874 0.4064)
			(stroke
				(width 0.1524)
				(type default)
			)
			(layer "F.SilkS")
		)
		(fp_line
			(start -0.67945 -0.305054)
			(end -0.12065 -0.305054)
			(stroke
				(width 0.1)
				(type default)
			)
			(layer "F.Fab")
		)
		(fp_line
			(start -0.67945 0.3048)
			(end -0.67945 -0.305054)
			(stroke
				(width 0.1)
				(type default)
			)
			(layer "F.Fab")
		)
		(fp_line
			(start -0.12065 -0.305054)
			(end -0.12065 -0.2794)
			(stroke
				(width 0.1)
				(type default)
			)
			(layer "F.Fab")
		)
		(fp_line
			(start -0.12065 -0.2794)
			(end 0.12065 -0.2794)
			(stroke
				(width 0.1)
				(type default)
			)
			(layer "F.Fab")
		)
		(fp_line
			(start -0.12065 0.2794)
			(end -0.12065 0.3048)
			(stroke
				(width 0.1)
				(type default)
			)
			(layer "F.Fab")
		)
		(fp_line
			(start -0.12065 0.3048)
			(end -0.67945 0.3048)
			(stroke
				(width 0.1)
				(type default)
			)
			(layer "F.Fab")
		)
		(fp_line
			(start 0.120396 0.2794)
			(end -0.12065 0.2794)
			(stroke
				(width 0.1)
				(type default)
			)
			(layer "F.Fab")
		)
		(fp_line
			(start 0.120396 0.3048)
			(end 0.120396 0.2794)
			(stroke
				(width 0.1)
				(type default)
			)
			(layer "F.Fab")
		)
		(fp_line
			(start 0.12065 -0.3048)
			(end 0.67945 -0.3048)
			(stroke
				(width 0.1)
				(type default)
			)
			(layer "F.Fab")
		)
		(fp_line
			(start 0.12065 -0.2794)
			(end 0.12065 -0.3048)
			(stroke
				(width 0.1)
				(type default)
			)
			(layer "F.Fab")
		)
		(fp_line
			(start 0.67945 -0.3048)
			(end 0.67945 0.3048)
			(stroke
				(width 0.1)
				(type default)
			)
			(layer "F.Fab")
		)
		(fp_line
			(start 0.67945 0.3048)
			(end 0.120396 0.3048)
			(stroke
				(width 0.1)
				(type default)
			)
			(layer "F.Fab")
		)
		(pad "1" smd circle
			(at -0.40005 0)
			(size 0 0)
			(layers "F.Cu" "F.Mask" "F.Paste")
			(net "P3V3")
		)
		(pad "2" smd circle
			(at 0.40005 0)
			(size 0 0)
			(layers "F.Cu" "F.Mask" "F.Paste")
			(net "PVCCFA_EHV_FIVRA_CPU1_PVCC1")
		)
	)
)
